(kicad_pcb
	(version 20260206)
	(generator "pcbnew")
	(generator_version "10.0")
	(general
		(thickness 1.6)
		(legacy_teardrops no)
	)
	(paper "A4")
	(title_block
		(title "03242023_DA0F0TMBIJ0_F0T_Motherboard_J_brd_V01_OCP.brd")
		(comment 1 "Grand Teton / footprints 4748-4752 of 6105")
	)
	(layers
		(0 "F.Cu" signal "TOP")
		(4 "In1.Cu" signal "GND")
		(6 "In2.Cu" signal "IN1")
		(8 "In3.Cu" signal "GND1")
		(10 "In4.Cu" signal "IN2")
		(12 "In5.Cu" signal "GND2")
		(14 "In6.Cu" signal "IN3")
		(16 "In7.Cu" signal "GND3")
		(18 "In8.Cu" signal "VCC")
		(20 "In9.Cu" signal "VCC1")
		(22 "In10.Cu" signal "GND4")
		(24 "In11.Cu" signal "IN4")
		(26 "In12.Cu" signal "GND5")
		(28 "In13.Cu" signal "IN5")
		(30 "In14.Cu" signal "GND6")
		(32 "In15.Cu" signal "IN6")
		(34 "In16.Cu" signal "GND7")
		(2 "B.Cu" signal "BOTTOM")
		(9 "F.Adhes" user "F.Adhesive")
		(11 "B.Adhes" user "B.Adhesive")
		(13 "F.Paste" user "Package Geometry/Pastemask Top")
		(15 "B.Paste" user "Package Geometry/Pastemask Bottom")
		(5 "F.SilkS" user "Ref Des/Silkscreen Top")
		(7 "B.SilkS" user "Ref Des/Silkscreen Bottom")
		(1 "F.Mask" user "Board Geometry/Soldermask Top")
		(3 "B.Mask" user "Board Geometry/Soldermask Bottom")
		(17 "Dwgs.User" user "User.Drawings")
		(19 "Cmts.User" user "User.Comments")
		(21 "Eco1.User" user "User.Eco1")
		(23 "Eco2.User" user "User.Eco2")
		(25 "Edge.Cuts" user "Board Geometry/Outline")
		(27 "Margin" user)
		(31 "F.CrtYd" user "Package Geometry/Place Bound Top")
		(29 "B.CrtYd" user "Package Geometry/Place Bound Bottom")
		(35 "F.Fab" user "Ref Des/Assembly Top")
		(33 "B.Fab" user "Ref Des/Assembly Bottom")
	)
	(footprint ""
		(layer "B.Cu")
		(at 245.25478 -396.43304 90)
		(property "Reference" "PC1751"
			(at 0 0 90)
			(layer "B.SilkS")
			(hide yes)
			(effects
				(font
					(size 1.27 1.27)
				)
				(justify mirror)
			)
		)
		(property "Value" ""
			(at 0 0 90)
			(layer "B.Fab")
			(effects
				(font
					(size 1.27 1.27)
				)
				(justify mirror)
			)
		)
		(duplicate_pad_numbers_are_jumpers no)
		(fp_line
			(start 0.7874 -0.4064)
			(end -0.7874 -0.4064)
			(stroke
				(width 0.1524)
				(type default)
			)
			(layer "B.SilkS")
		)
		(fp_line
			(start -0.7874 -0.4064)
			(end -0.7874 0.4064)
			(stroke
				(width 0.1524)
				(type default)
			)
			(layer "B.SilkS")
		)
		(fp_line
			(start 0.7874 0.4064)
			(end 0.7874 -0.4064)
			(stroke
				(width 0.1524)
				(type default)
			)
			(layer "B.SilkS")
		)
		(fp_line
			(start -0.7874 0.4064)
			(end 0.7874 0.4064)
			(stroke
				(width 0.1524)
				(type default)
			)
			(layer "B.SilkS")
		)
		(fp_line
			(start 0.67945 -0.305054)
			(end 0.12065 -0.305054)
			(stroke
				(width 0.1)
				(type default)
			)
			(layer "B.Fab")
		)
		(fp_line
			(start 0.12065 -0.305054)
			(end 0.12065 -0.2794)
			(stroke
				(width 0.1)
				(type default)
			)
			(layer "B.Fab")
		)
		(fp_line
			(start -0.12065 -0.3048)
			(end -0.67945 -0.3048)
			(stroke
				(width 0.1)
				(type default)
			)
			(layer "B.Fab")
		)
		(fp_line
			(start -0.67945 -0.3048)
			(end -0.67945 0.3048)
			(stroke
				(width 0.1)
				(type default)
			)
			(layer "B.Fab")
		)
		(fp_line
			(start 0.12065 -0.2794)
			(end -0.12065 -0.2794)
			(stroke
				(width 0.1)
				(type default)
			)
			(layer "B.Fab")
		)
		(fp_line
			(start -0.12065 -0.2794)
			(end -0.12065 -0.3048)
			(stroke
				(width 0.1)
				(type default)
			)
			(layer "B.Fab")
		)
		(fp_line
			(start 0.12065 0.2794)
			(end 0.12065 0.3048)
			(stroke
				(width 0.1)
				(type default)
			)
			(layer "B.Fab")
		)
		(fp_line
			(start -0.120396 0.2794)
			(end 0.12065 0.2794)
			(stroke
				(width 0.1)
				(type default)
			)
			(layer "B.Fab")
		)
		(fp_line
			(start 0.67945 0.3048)
			(end 0.67945 -0.305054)
			(stroke
				(width 0.1)
				(type default)
			)
			(layer "B.Fab")
		)
		(fp_line
			(start 0.12065 0.3048)
			(end 0.67945 0.3048)
			(stroke
				(width 0.1)
				(type default)
			)
			(layer "B.Fab")
		)
		(fp_line
			(start -0.120396 0.3048)
			(end -0.120396 0.2794)
			(stroke
				(width 0.1)
				(type default)
			)
			(layer "B.Fab")
		)
		(fp_line
			(start -0.67945 0.3048)
			(end -0.120396 0.3048)
			(stroke
				(width 0.1)
				(type default)
			)
			(layer "B.Fab")
		)
		(pad "1" smd circle
			(at 0.40005 0 270)
			(size 0 0)
			(layers "B.Cu" "B.Mask" "B.Paste")
			(net "P12V_HSC_GATE_RC")
		)
		(pad "2" smd circle
			(at -0.40005 0 270)
			(size 0 0)
			(layers "B.Cu" "B.Mask" "B.Paste")
			(net "P12V_HSC_GATE2")
		)
	)
	(footprint ""
		(layer "B.Cu")
		(at 193.38163 -127.422148 180)
		(property "Reference" "R4519"
			(at 0 0 0)
			(layer "B.SilkS")
			(hide yes)
			(effects
				(font
					(size 1.27 1.27)
				)
				(justify mirror)
			)
		)
		(property "Value" ""
			(at 0 0 0)
			(layer "B.Fab")
			(effects
				(font
					(size 1.27 1.27)
				)
				(justify mirror)
			)
		)
		(duplicate_pad_numbers_are_jumpers no)
		(fp_line
			(start 0.7874 0.4064)
			(end 0.7874 -0.4064)
			(stroke
				(width 0.1524)
				(type default)
			)
			(layer "B.SilkS")
		)
		(fp_line
			(start 0.7874 -0.4064)
			(end -0.7874 -0.4064)
			(stroke
				(width 0.1524)
				(type default)
			)
			(layer "B.SilkS")
		)
		(fp_line
			(start -0.7874 0.4064)
			(end 0.7874 0.4064)
			(stroke
				(width 0.1524)
				(type default)
			)
			(layer "B.SilkS")
		)
		(fp_line
			(start -0.7874 -0.4064)
			(end -0.7874 0.4064)
			(stroke
				(width 0.1524)
				(type default)
			)
			(layer "B.SilkS")
		)
		(fp_line
			(start 0.67945 0.3048)
			(end 0.67945 -0.305054)
			(stroke
				(width 0.1)
				(type default)
			)
			(layer "B.Fab")
		)
		(fp_line
			(start 0.67945 -0.305054)
			(end 0.12065 -0.305054)
			(stroke
				(width 0.1)
				(type default)
			)
			(layer "B.Fab")
		)
		(fp_line
			(start 0.12065 0.3048)
			(end 0.67945 0.3048)
			(stroke
				(width 0.1)
				(type default)
			)
			(layer "B.Fab")
		)
		(fp_line
			(start 0.12065 0.2794)
			(end 0.12065 0.3048)
			(stroke
				(width 0.1)
				(type default)
			)
			(layer "B.Fab")
		)
		(fp_line
			(start 0.12065 -0.2794)
			(end -0.12065 -0.2794)
			(stroke
				(width 0.1)
				(type default)
			)
			(layer "B.Fab")
		)
		(fp_line
			(start 0.12065 -0.305054)
			(end 0.12065 -0.2794)
			(stroke
				(width 0.1)
				(type default)
			)
			(layer "B.Fab")
		)
		(fp_line
			(start -0.120396 0.3048)
			(end -0.120396 0.2794)
			(stroke
				(width 0.1)
				(type default)
			)
			(layer "B.Fab")
		)
		(fp_line
			(start -0.120396 0.2794)
			(end 0.12065 0.2794)
			(stroke
				(width 0.1)
				(type default)
			)
			(layer "B.Fab")
		)
		(fp_line
			(start -0.12065 -0.2794)
			(end -0.12065 -0.3048)
			(stroke
				(width 0.1)
				(type default)
			)
			(layer "B.Fab")
		)
		(fp_line
			(start -0.12065 -0.3048)
			(end -0.67945 -0.3048)
			(stroke
				(width 0.1)
				(type default)
			)
			(layer "B.Fab")
		)
		(fp_line
			(start -0.67945 0.3048)
			(end -0.120396 0.3048)
			(stroke
				(width 0.1)
				(type default)
			)
			(layer "B.Fab")
		)
		(fp_line
			(start -0.67945 -0.3048)
			(end -0.67945 0.3048)
			(stroke
				(width 0.1)
				(type default)
			)
			(layer "B.Fab")
		)
		(pad "1" smd circle
			(at 0.40005 0)
			(size 0 0)
			(layers "B.Cu" "B.Mask" "B.Paste")
			(net "P3V3")
		)
		(pad "2" smd circle
			(at -0.40005 0)
			(size 0 0)
			(layers "B.Cu" "B.Mask" "B.Paste")
			(net "CLK_GPU_1_OE_N")
		)
	)
	(footprint ""
		(layer "B.Cu")
		(at 62.53988 -8.981948 90)
		(property "Reference" "C1837"
			(at 0 0 90)
			(layer "B.SilkS")
			(hide yes)
			(effects
				(font
					(size 1.27 1.27)
				)
				(justify mirror)
			)
		)
		(property "Value" ""
			(at 0 0 90)
			(layer "B.Fab")
			(effects
				(font
					(size 1.27 1.27)
				)
				(justify mirror)
			)
		)
		(duplicate_pad_numbers_are_jumpers no)
		(fp_line
			(start 0.7874 -0.4064)
			(end -0.7874 -0.4064)
			(stroke
				(width 0.1524)
				(type default)
			)
			(layer "B.SilkS")
		)
		(fp_line
			(start -0.7874 -0.4064)
			(end -0.7874 0.4064)
			(stroke
				(width 0.1524)
				(type default)
			)
			(layer "B.SilkS")
		)
		(fp_line
			(start 0.7874 0.4064)
			(end 0.7874 -0.4064)
			(stroke
				(width 0.1524)
				(type default)
			)
			(layer "B.SilkS")
		)
		(fp_line
			(start -0.7874 0.4064)
			(end 0.7874 0.4064)
			(stroke
				(width 0.1524)
				(type default)
			)
			(layer "B.SilkS")
		)
		(fp_line
			(start 0.67945 -0.305054)
			(end 0.12065 -0.305054)
			(stroke
				(width 0.1)
				(type default)
			)
			(layer "B.Fab")
		)
		(fp_line
			(start 0.12065 -0.305054)
			(end 0.12065 -0.2794)
			(stroke
				(width 0.1)
				(type default)
			)
			(layer "B.Fab")
		)
		(fp_line
			(start -0.12065 -0.3048)
			(end -0.67945 -0.3048)
			(stroke
				(width 0.1)
				(type default)
			)
			(layer "B.Fab")
		)
		(fp_line
			(start -0.67945 -0.3048)
			(end -0.67945 0.3048)
			(stroke
				(width 0.1)
				(type default)
			)
			(layer "B.Fab")
		)
		(fp_line
			(start 0.12065 -0.2794)
			(end -0.12065 -0.2794)
			(stroke
				(width 0.1)
				(type default)
			)
			(layer "B.Fab")
		)
		(fp_line
			(start -0.12065 -0.2794)
			(end -0.12065 -0.3048)
			(stroke
				(width 0.1)
				(type default)
			)
			(layer "B.Fab")
		)
		(fp_line
			(start 0.12065 0.2794)
			(end 0.12065 0.3048)
			(stroke
				(width 0.1)
				(type default)
			)
			(layer "B.Fab")
		)
		(fp_line
			(start -0.120396 0.2794)
			(end 0.12065 0.2794)
			(stroke
				(width 0.1)
				(type default)
			)
			(layer "B.Fab")
		)
		(fp_line
			(start 0.67945 0.3048)
			(end 0.67945 -0.305054)
			(stroke
				(width 0.1)
				(type default)
			)
			(layer "B.Fab")
		)
		(fp_line
			(start 0.12065 0.3048)
			(end 0.67945 0.3048)
			(stroke
				(width 0.1)
				(type default)
			)
			(layer "B.Fab")
		)
		(fp_line
			(start -0.120396 0.3048)
			(end -0.120396 0.2794)
			(stroke
				(width 0.1)
				(type default)
			)
			(layer "B.Fab")
		)
		(fp_line
			(start -0.67945 0.3048)
			(end -0.120396 0.3048)
			(stroke
				(width 0.1)
				(type default)
			)
			(layer "B.Fab")
		)
		(pad "1" smd circle
			(at 0.40005 0 270)
			(size 0 0)
			(layers "B.Cu" "B.Mask" "B.Paste")
			(net "P3V3_OCP_V3_2")
		)
		(pad "2" smd circle
			(at -0.40005 0 270)
			(size 0 0)
			(layers "B.Cu" "B.Mask" "B.Paste")
			(net "GND")
		)
	)
	(footprint ""
		(layer "B.Cu")
		(at 260.731508 8.003794 180)
		(property "Reference" "J118"
			(at 4.345178 -1.648206 270)
			(unlocked yes)
			(layer "B.SilkS")
			(effects
				(font
					(size 0.7874 0.5842)
					(thickness 0.1524)
				)
				(justify left mirror)
			)
		)
		(property "Value" ""
			(at 0 0 0)
			(layer "B.Fab")
			(effects
				(font
					(size 1.27 1.27)
				)
				(justify mirror)
			)
		)
		(duplicate_pad_numbers_are_jumpers no)
		(fp_line
			(start 1.2192 2.1082)
			(end 1.2192 -2.1082)
			(stroke
				(width 0.1524)
				(type default)
			)
			(layer "B.SilkS")
		)
		(fp_line
			(start 1.2192 -2.1082)
			(end -1.2192 -2.1082)
			(stroke
				(width 0.1524)
				(type default)
			)
			(layer "B.SilkS")
		)
		(fp_line
			(start -1.2192 2.1082)
			(end 1.2192 2.1082)
			(stroke
				(width 0.1524)
				(type default)
			)
			(layer "B.SilkS")
		)
		(fp_line
			(start -1.2192 -2.1082)
			(end -1.2192 2.1082)
			(stroke
				(width 0.1524)
				(type default)
			)
			(layer "B.SilkS")
		)
		(pad "" np_thru_hole circle
			(at -3.4671 -1.27 90)
			(size 1.0414 1.0414)
			(drill 1.0414)
			(layers "*.Cu" "*.Mask")
			(clearance 0.381)
			(thermal_gap 0.381)
		)
		(pad "" np_thru_hole circle
			(at -3.4671 1.27 90)
			(size 1.0414 1.0414)
			(drill 1.0414)
			(layers "*.Cu" "*.Mask")
			(clearance 0.381)
			(thermal_gap 0.381)
		)
		(pad "" np_thru_hole circle
			(at 2.8829 -1.27 90)
			(size 1.0414 1.0414)
			(drill 1.0414)
			(layers "*.Cu" "*.Mask")
			(clearance 0.381)
			(thermal_gap 0.381)
		)
		(pad "" np_thru_hole circle
			(at 2.8829 1.27 90)
			(size 1.0414 1.0414)
			(drill 1.0414)
			(layers "*.Cu" "*.Mask")
			(clearance 0.381)
			(thermal_gap 0.381)
		)
		(pad "1" smd rect
			(at -0.8255 -0.249936 90)
			(size 0.3048 0.508)
			(layers "B.Cu" "B.Mask" "B.Paste")
			(net "DELTA_L_85_10INCH_IN5_DP")
		)
		(pad "2" smd rect
			(at -0.8255 0.249936 90)
			(size 0.3048 0.508)
			(layers "B.Cu" "B.Mask" "B.Paste")
			(net "DELTA_L_85_10INCH_IN5_DN")
		)
		(pad "3" smd circle
			(at 0 0)
			(size 0 0)
			(layers "B.Cu" "B.Mask" "B.Paste")
			(net "DELTA_L_GND_1")
		)
		(zone
			(layers "F.Cu" "B.Cu" "In1.Cu" "In2.Cu" "In3.Cu" "In4.Cu" "In5.Cu" "In6.Cu"
				"In7.Cu" "In8.Cu" "In9.Cu" "In10.Cu" "In11.Cu" "In12.Cu" "In13.Cu" "In14.Cu"
				"In15.Cu" "In16.Cu"
			)
			(hatch none 0.5)
			(connect_pads
				(clearance 0)
			)
			(min_thickness 0.25)
			(keepout
				(tracks not_allowed)
				(vias allowed)
				(pads allowed)
				(copperpour not_allowed)
				(footprints allowed)
			)
			(placement
				(enabled no)
				(sheetname "")
			)
			(fill
				(thermal_gap 0.5)
				(thermal_bridge_width 0.5)
				(island_removal_mode 0)
			)
			(polygon
				(pts
					(arc
						(start 258.775708 6.733794)
						(mid 256.921508 6.733794)
						(end 258.775708 6.733794)
					)
				)
			)
		)
		(zone
			(layers "F.Cu" "B.Cu" "In1.Cu" "In2.Cu" "In3.Cu" "In4.Cu" "In5.Cu" "In6.Cu"
				"In7.Cu" "In8.Cu" "In9.Cu" "In10.Cu" "In11.Cu" "In12.Cu" "In13.Cu" "In14.Cu"
				"In15.Cu" "In16.Cu"
			)
			(hatch none 0.5)
			(connect_pads
				(clearance 0)
			)
			(min_thickness 0.25)
			(keepout
				(tracks not_allowed)
				(vias allowed)
				(pads allowed)
				(copperpour not_allowed)
				(footprints allowed)
			)
			(placement
				(enabled no)
				(sheetname "")
			)
			(fill
				(thermal_gap 0.5)
				(thermal_bridge_width 0.5)
				(island_removal_mode 0)
			)
			(polygon
				(pts
					(arc
						(start 258.775708 9.273794)
						(mid 256.921508 9.273794)
						(end 258.775708 9.273794)
					)
				)
			)
		)
		(zone
			(layers "F.Cu" "B.Cu" "In1.Cu" "In2.Cu" "In3.Cu" "In4.Cu" "In5.Cu" "In6.Cu"
				"In7.Cu" "In8.Cu" "In9.Cu" "In10.Cu" "In11.Cu" "In12.Cu" "In13.Cu" "In14.Cu"
				"In15.Cu" "In16.Cu"
			)
			(hatch none 0.5)
			(connect_pads
				(clearance 0)
			)
			(min_thickness 0.25)
			(keepout
				(tracks not_allowed)
				(vias allowed)
				(pads allowed)
				(copperpour not_allowed)
				(footprints allowed)
			)
			(placement
				(enabled no)
				(sheetname "")
			)
			(fill
				(thermal_gap 0.5)
				(thermal_bridge_width 0.5)
				(island_removal_mode 0)
			)
			(polygon
				(pts
					(arc
						(start 265.125708 6.733794)
						(mid 263.271508 6.733794)
						(end 265.125708 6.733794)
					)
				)
			)
		)
		(zone
			(layers "F.Cu" "B.Cu" "In1.Cu" "In2.Cu" "In3.Cu" "In4.Cu" "In5.Cu" "In6.Cu"
				"In7.Cu" "In8.Cu" "In9.Cu" "In10.Cu" "In11.Cu" "In12.Cu" "In13.Cu" "In14.Cu"
				"In15.Cu" "In16.Cu"
			)
			(hatch none 0.5)
			(connect_pads
				(clearance 0)
			)
			(min_thickness 0.25)
			(keepout
				(tracks not_allowed)
				(vias allowed)
				(pads allowed)
				(copperpour not_allowed)
				(footprints allowed)
			)
			(placement
				(enabled no)
				(sheetname "")
			)
			(fill
				(thermal_gap 0.5)
				(thermal_bridge_width 0.5)
				(island_removal_mode 0)
			)
			(polygon
				(pts
					(arc
						(start 265.125708 9.273794)
						(mid 263.271508 9.273794)
						(end 265.125708 9.273794)
					)
				)
			)
		)
		(zone
			(layer "B.Cu")
			(hatch none 0.5)
			(connect_pads
				(clearance 0)
			)
			(min_thickness 0.25)
			(keepout
				(tracks not_allowed)
				(vias allowed)
				(pads allowed)
				(copperpour not_allowed)
				(footprints allowed)
			)
			(placement
				(enabled no)
				(sheetname "")
			)
			(fill
				(thermal_gap 0.5)
				(thermal_bridge_width 0.5)
				(island_removal_mode 0)
			)
			(polygon
				(pts
					(xy 261.849108 8.552434) (xy 261.849108 8.45693) (xy 261.252208 8.45693) (xy 261.252208 8.05053)
					(xy 261.849108 8.05053) (xy 261.849108 7.957058) (xy 261.252208 7.957058) (xy 261.252208 7.550658)
					(xy 261.849108 7.550658) (xy 261.849108 7.455154) (xy 261.150608 7.455154) (xy 261.150608 8.552434)
				)
			)
		)
	)
	(footprint ""
		(layer "B.Cu")
		(at 433.273962 -317.102998 90)
		(property "Reference" "R2492"
			(at 0 0 90)
			(layer "B.SilkS")
			(hide yes)
			(effects
				(font
					(size 1.27 1.27)
				)
				(justify mirror)
			)
		)
		(property "Value" ""
			(at 0 0 90)
			(layer "B.Fab")
			(effects
				(font
					(size 1.27 1.27)
				)
				(justify mirror)
			)
		)
		(duplicate_pad_numbers_are_jumpers no)
		(fp_line
			(start 0.7874 -0.4064)
			(end -0.7874 -0.4064)
			(stroke
				(width 0.1524)
				(type default)
			)
			(layer "B.SilkS")
		)
		(fp_line
			(start -0.7874 -0.4064)
			(end -0.7874 0.4064)
			(stroke
				(width 0.1524)
				(type default)
			)
			(layer "B.SilkS")
		)
		(fp_line
			(start 0.7874 0.4064)
			(end 0.7874 -0.4064)
			(stroke
				(width 0.1524)
				(type default)
			)
			(layer "B.SilkS")
		)
		(fp_line
			(start -0.7874 0.4064)
			(end 0.7874 0.4064)
			(stroke
				(width 0.1524)
				(type default)
			)
			(layer "B.SilkS")
		)
		(fp_line
			(start 0.67945 -0.305054)
			(end 0.12065 -0.305054)
			(stroke
				(width 0.1)
				(type default)
			)
			(layer "B.Fab")
		)
		(fp_line
			(start 0.12065 -0.305054)
			(end 0.12065 -0.2794)
			(stroke
				(width 0.1)
				(type default)
			)
			(layer "B.Fab")
		)
		(fp_line
			(start -0.12065 -0.3048)
			(end -0.67945 -0.3048)
			(stroke
				(width 0.1)
				(type default)
			)
			(layer "B.Fab")
		)
		(fp_line
			(start -0.67945 -0.3048)
			(end -0.67945 0.3048)
			(stroke
				(width 0.1)
				(type default)
			)
			(layer "B.Fab")
		)
		(fp_line
			(start 0.12065 -0.2794)
			(end -0.12065 -0.2794)
			(stroke
				(width 0.1)
				(type default)
			)
			(layer "B.Fab")
		)
		(fp_line
			(start -0.12065 -0.2794)
			(end -0.12065 -0.3048)
			(stroke
				(width 0.1)
				(type default)
			)
			(layer "B.Fab")
		)
		(fp_line
			(start 0.12065 0.2794)
			(end 0.12065 0.3048)
			(stroke
				(width 0.1)
				(type default)
			)
			(layer "B.Fab")
		)
		(fp_line
			(start -0.120396 0.2794)
			(end 0.12065 0.2794)
			(stroke
				(width 0.1)
				(type default)
			)
			(layer "B.Fab")
		)
		(fp_line
			(start 0.67945 0.3048)
			(end 0.67945 -0.305054)
			(stroke
				(width 0.1)
				(type default)
			)
			(layer "B.Fab")
		)
		(fp_line
			(start 0.12065 0.3048)
			(end 0.67945 0.3048)
			(stroke
				(width 0.1)
				(type default)
			)
			(layer "B.Fab")
		)
		(fp_line
			(start -0.120396 0.3048)
			(end -0.120396 0.2794)
			(stroke
				(width 0.1)
				(type default)
			)
			(layer "B.Fab")
		)
		(fp_line
			(start -0.67945 0.3048)
			(end -0.120396 0.3048)
			(stroke
				(width 0.1)
				(type default)
			)
			(layer "B.Fab")
		)
		(pad "1" smd circle
			(at 0.40005 0 270)
			(size 0 0)
			(layers "B.Cu" "B.Mask" "B.Paste")
			(net "PWRGD_FAIL_CPU0_EF")
		)
		(pad "2" smd circle
			(at -0.40005 0 270)
			(size 0 0)
			(layers "B.Cu" "B.Mask" "B.Paste")
			(net "PWRGD_FAIL_CPU0_EF_R1")
		)
	)
)
